(kicad_pcb
	(version 20260206)
	(generator "pcbnew")
	(generator_version "10.0")
	(general
		(thickness 1.6)
		(legacy_teardrops no)
	)
	(paper "A4")
	(title_block
		(title "12092022_DA0F0TFB6D0_F0T_FAN_BOARD_MP5048_D_brd_v02_OCP.brd")
		(comment 1 "Grand Teton / footprints 882-886 of 924")
	)
	(layers
		(0 "F.Cu" signal "TOP")
		(4 "In1.Cu" signal "GND")
		(6 "In2.Cu" signal "IN1")
		(8 "In3.Cu" signal "IN2")
		(10 "In4.Cu" signal "GND1")
		(2 "B.Cu" signal "BOTTOM")
		(9 "F.Adhes" user "F.Adhesive")
		(11 "B.Adhes" user "B.Adhesive")
		(13 "F.Paste" user "Package Geometry/Pastemask Top")
		(15 "B.Paste" user "Package Geometry/Pastemask Bottom")
		(5 "F.SilkS" user "Ref Des/Silkscreen Top")
		(7 "B.SilkS" user "Ref Des/Silkscreen Bottom")
		(1 "F.Mask" user "Board Geometry/Soldermask Top")
		(3 "B.Mask" user "Board Geometry/Soldermask Bottom")
		(17 "Dwgs.User" user "User.Drawings")
		(19 "Cmts.User" user "User.Comments")
		(21 "Eco1.User" user "User.Eco1")
		(23 "Eco2.User" user "User.Eco2")
		(25 "Edge.Cuts" user "Board Geometry/Outline")
		(27 "Margin" user)
		(31 "F.CrtYd" user "Package Geometry/Place Bound Top")
		(29 "B.CrtYd" user "Package Geometry/Place Bound Bottom")
		(35 "F.Fab" user "Ref Des/Assembly Top")
		(33 "B.Fab" user "Ref Des/Assembly Bottom")
	)
	(footprint ""
		(layer "B.Cu")
		(at 5.50799 -274.971256 -90)
		(property "Reference" "PD13"
			(at 4.7752 -3.749548 270)
			(unlocked yes)
			(layer "B.SilkS")
			(effects
				(font
					(size 0.7874 0.5842)
					(thickness 0.1524)
				)
				(justify left mirror)
			)
		)
		(property "Value" ""
			(at 0 0 90)
			(layer "B.Fab")
			(effects
				(font
					(size 1.27 1.27)
				)
				(justify mirror)
			)
		)
		(duplicate_pad_numbers_are_jumpers no)
		(fp_line
			(start -5.334 3.109976)
			(end -4.8133 3.109976)
			(stroke
				(width 0.1524)
				(type default)
			)
			(layer "B.SilkS")
		)
		(fp_line
			(start -5.334 3.109976)
			(end -5.334 0)
			(stroke
				(width 0.1524)
				(type default)
			)
			(layer "B.SilkS")
		)
		(fp_line
			(start -5.207 3.109976)
			(end -5.207 -3.109976)
			(stroke
				(width 0.1524)
				(type default)
			)
			(layer "B.SilkS")
		)
		(fp_line
			(start -5.1308 3.109976)
			(end -5.1308 -3.109976)
			(stroke
				(width 0.1524)
				(type default)
			)
			(layer "B.SilkS")
		)
		(fp_line
			(start -5.0292 3.109976)
			(end -5.0292 -3.109976)
			(stroke
				(width 0.1524)
				(type default)
			)
			(layer "B.SilkS")
		)
		(fp_line
			(start -4.9276 3.109976)
			(end -4.9276 -3.109976)
			(stroke
				(width 0.1524)
				(type default)
			)
			(layer "B.SilkS")
		)
		(fp_line
			(start -4.826 3.109976)
			(end 4.826 3.109976)
			(stroke
				(width 0.1524)
				(type default)
			)
			(layer "B.SilkS")
		)
		(fp_line
			(start 4.826 3.109976)
			(end 4.826 0)
			(stroke
				(width 0.1524)
				(type default)
			)
			(layer "B.SilkS")
		)
		(fp_line
			(start -1.143 1.397)
			(end -1.143 -1.397)
			(stroke
				(width 0.1524)
				(type default)
			)
			(layer "B.SilkS")
		)
		(fp_line
			(start 1.016 1.016)
			(end -1.016 0)
			(stroke
				(width 0.1524)
				(type default)
			)
			(layer "B.SilkS")
		)
		(fp_line
			(start -5.334 0)
			(end -5.334 -3.109976)
			(stroke
				(width 0.1524)
				(type default)
			)
			(layer "B.SilkS")
		)
		(fp_line
			(start -4.826 0)
			(end -4.826 3.109976)
			(stroke
				(width 0.1524)
				(type default)
			)
			(layer "B.SilkS")
		)
		(fp_line
			(start -1.143 0)
			(end -1.8034 0)
			(stroke
				(width 0.1524)
				(type default)
			)
			(layer "B.SilkS")
		)
		(fp_line
			(start -1.143 0)
			(end 1.016 -1.016)
			(stroke
				(width 0.1524)
				(type default)
			)
			(layer "B.SilkS")
		)
		(fp_line
			(start 1.0922 0)
			(end 1.7018 0)
			(stroke
				(width 0.1524)
				(type default)
			)
			(layer "B.SilkS")
		)
		(fp_line
			(start 4.826 0)
			(end 4.826 -3.109976)
			(stroke
				(width 0.1524)
				(type default)
			)
			(layer "B.SilkS")
		)
		(fp_line
			(start 1.016 -1.016)
			(end 1.016 1.016)
			(stroke
				(width 0.1524)
				(type default)
			)
			(layer "B.SilkS")
		)
		(fp_line
			(start -4.826 -3.109976)
			(end -4.826 0)
			(stroke
				(width 0.1524)
				(type default)
			)
			(layer "B.SilkS")
		)
		(fp_line
			(start -4.8133 -3.109976)
			(end -5.3467 -3.109976)
			(stroke
				(width 0.1524)
				(type default)
			)
			(layer "B.SilkS")
		)
		(fp_line
			(start 4.826 -3.109976)
			(end -4.826 -3.109976)
			(stroke
				(width 0.1524)
				(type default)
			)
			(layer "B.SilkS")
		)
		(fp_line
			(start -3.554984 3.109976)
			(end 3.554984 3.109976)
			(stroke
				(width 0.1)
				(type default)
			)
			(layer "B.Fab")
		)
		(fp_line
			(start 3.554984 3.109976)
			(end 3.554984 -3.109976)
			(stroke
				(width 0.1)
				(type default)
			)
			(layer "B.Fab")
		)
		(fp_line
			(start -1.143 1.397)
			(end -1.143 -1.397)
			(stroke
				(width 0.1)
				(type default)
			)
			(layer "B.Fab")
		)
		(fp_line
			(start 1.016 1.016)
			(end -1.016 0)
			(stroke
				(width 0.1)
				(type default)
			)
			(layer "B.Fab")
		)
		(fp_line
			(start -1.143 0)
			(end -1.8034 0)
			(stroke
				(width 0.1)
				(type default)
			)
			(layer "B.Fab")
		)
		(fp_line
			(start -1.143 0)
			(end 1.016 -1.016)
			(stroke
				(width 0.1)
				(type default)
			)
			(layer "B.Fab")
		)
		(fp_line
			(start 1.0922 0)
			(end 1.7018 0)
			(stroke
				(width 0.1)
				(type default)
			)
			(layer "B.Fab")
		)
		(fp_line
			(start 1.016 -1.016)
			(end 1.016 1.016)
			(stroke
				(width 0.1)
				(type default)
			)
			(layer "B.Fab")
		)
		(fp_line
			(start -3.554984 -3.109976)
			(end -3.554984 3.109976)
			(stroke
				(width 0.1)
				(type default)
			)
			(layer "B.Fab")
		)
		(fp_line
			(start 3.554984 -3.109976)
			(end -3.554984 -3.109976)
			(stroke
				(width 0.1)
				(type default)
			)
			(layer "B.Fab")
		)
		(fp_text user "+"
			(at 4.689856 2.93624 90)
			(unlocked yes)
			(layer "B.SilkS")
			(effects
				(font
					(size 1.905 1.4224)
					(thickness 0.1524)
				)
				(justify left mirror)
			)
		)
		(fp_text user "-"
			(at -6.613144 2.04724 90)
			(unlocked yes)
			(layer "B.SilkS")
			(effects
				(font
					(size 1.905 1.4224)
					(thickness 0.1524)
				)
				(justify left mirror)
			)
		)
		(fp_text user "-"
			(at -6.6802 0.22225 90)
			(unlocked yes)
			(layer "B.Fab")
			(effects
				(font
					(size 1.905 1.4224)
					(thickness 0.1524)
				)
				(justify left mirror)
			)
		)
		(fp_text user "+"
			(at 4.5466 0.19685 90)
			(unlocked yes)
			(layer "B.Fab")
			(effects
				(font
					(size 1.905 1.4224)
					(thickness 0.1524)
				)
				(justify left mirror)
			)
		)
		(pad "A" smd rect
			(at 3.400044 0 270)
			(size 2.5146 3.302)
			(layers "B.Cu" "B.Mask" "B.Paste")
			(net "GND")
		)
		(pad "C" smd rect
			(at -3.400044 0 270)
			(size 2.5146 3.302)
			(layers "B.Cu" "B.Mask" "B.Paste")
			(net "P52V_FAN_7")
		)
	)
	(footprint ""
		(layer "B.Cu")
		(at 5.596128 -230.088948)
		(property "Reference" "C2115"
			(at 0 0 0)
			(layer "B.SilkS")
			(hide yes)
			(effects
				(font
					(size 1.27 1.27)
				)
				(justify mirror)
			)
		)
		(property "Value" ""
			(at 0 0 0)
			(layer "B.Fab")
			(effects
				(font
					(size 1.27 1.27)
				)
				(justify mirror)
			)
		)
		(duplicate_pad_numbers_are_jumpers no)
		(fp_line
			(start -2.2098 -0.9398)
			(end -2.2098 0.9398)
			(stroke
				(width 0.1524)
				(type default)
			)
			(layer "B.SilkS")
		)
		(fp_line
			(start -2.2098 0.9398)
			(end 2.2098 0.9398)
			(stroke
				(width 0.1524)
				(type default)
			)
			(layer "B.SilkS")
		)
		(fp_line
			(start 2.2098 -0.9398)
			(end -2.2098 -0.9398)
			(stroke
				(width 0.1524)
				(type default)
			)
			(layer "B.SilkS")
		)
		(fp_line
			(start 2.2098 0.9398)
			(end 2.2098 -0.9398)
			(stroke
				(width 0.1524)
				(type default)
			)
			(layer "B.SilkS")
		)
		(fp_line
			(start -1.700022 -0.899922)
			(end -1.700022 0.899922)
			(stroke
				(width 0.1)
				(type default)
			)
			(layer "B.Fab")
		)
		(fp_line
			(start -1.700022 0.899922)
			(end 1.700022 0.899922)
			(stroke
				(width 0.1)
				(type default)
			)
			(layer "B.Fab")
		)
		(fp_line
			(start 1.700022 -0.899922)
			(end -1.700022 -0.899922)
			(stroke
				(width 0.1)
				(type default)
			)
			(layer "B.Fab")
		)
		(fp_line
			(start 1.700022 0.899922)
			(end 1.700022 -0.899922)
			(stroke
				(width 0.1)
				(type default)
			)
			(layer "B.Fab")
		)
		(pad "1" smd rect
			(at 1.4732 0)
			(size 1.1684 1.5748)
			(layers "B.Cu" "B.Mask" "B.Paste")
			(net "P52V_FAN_6")
		)
		(pad "2" smd rect
			(at -1.4732 0)
			(size 1.1684 1.5748)
			(layers "B.Cu" "B.Mask" "B.Paste")
			(net "GND")
		)
	)
	(footprint ""
		(layer "B.Cu")
		(at 12.334494 -255.905)
		(property "Reference" "U385"
			(at 0.111506 1.80467 0)
			(unlocked yes)
			(layer "B.SilkS")
			(effects
				(font
					(size 0.7874 0.5842)
					(thickness 0.1524)
				)
				(justify mirror)
			)
		)
		(property "Value" ""
			(at 0 0 0)
			(layer "B.Fab")
			(effects
				(font
					(size 1.27 1.27)
				)
				(justify mirror)
			)
		)
		(duplicate_pad_numbers_are_jumpers no)
		(fp_line
			(start -1.7018 -1.1176)
			(end -1.7018 1.1176)
			(stroke
				(width 0.1524)
				(type default)
			)
			(layer "B.SilkS")
		)
		(fp_line
			(start -1.7018 -1.1176)
			(end -0.254 -1.1176)
			(stroke
				(width 0.1524)
				(type default)
			)
			(layer "B.SilkS")
		)
		(fp_line
			(start -1.7018 1.1176)
			(end 1.7018 1.1176)
			(stroke
				(width 0.1524)
				(type default)
			)
			(layer "B.SilkS")
		)
		(fp_line
			(start -0.254 -1.1176)
			(end 0 -0.7112)
			(stroke
				(width 0.1524)
				(type default)
			)
			(layer "B.SilkS")
		)
		(fp_line
			(start 0 -0.7112)
			(end 0.254 -1.1176)
			(stroke
				(width 0.1524)
				(type default)
			)
			(layer "B.SilkS")
		)
		(fp_line
			(start 0.254 -1.1176)
			(end 1.7018 -1.1176)
			(stroke
				(width 0.1524)
				(type default)
			)
			(layer "B.SilkS")
		)
		(fp_line
			(start 1.7018 1.1176)
			(end 1.7018 -1.1176)
			(stroke
				(width 0.1524)
				(type default)
			)
			(layer "B.SilkS")
		)
		(fp_poly
			(pts
				(xy 1.8161 -0.675386) (xy 2.4003 -0.446786) (xy 2.4003 -0.878586)
			)
			(stroke
				(width 0)
				(type default)
			)
			(fill yes)
			(layer "B.SilkS")
		)
		(fp_line
			(start -1.5494 -1.1176)
			(end -1.5494 1.1176)
			(stroke
				(width 0.1)
				(type default)
			)
			(layer "B.Fab")
		)
		(fp_line
			(start -1.5494 -1.1176)
			(end -0.254 -1.1176)
			(stroke
				(width 0.1)
				(type default)
			)
			(layer "B.Fab")
		)
		(fp_line
			(start -1.5494 1.1176)
			(end 1.5494 1.1176)
			(stroke
				(width 0.1)
				(type default)
			)
			(layer "B.Fab")
		)
		(fp_line
			(start -0.254 -1.1176)
			(end 0.254 -1.1176)
			(stroke
				(width 0.1)
				(type default)
			)
			(layer "B.Fab")
		)
		(fp_line
			(start 0.254 -1.1176)
			(end 1.5494 -1.1176)
			(stroke
				(width 0.1)
				(type default)
			)
			(layer "B.Fab")
		)
		(fp_line
			(start 1.5494 1.1176)
			(end 1.5494 -1.1176)
			(stroke
				(width 0.1)
				(type default)
			)
			(layer "B.Fab")
		)
		(fp_poly
			(pts
				(xy 1.8161 -0.675386) (xy 2.4003 -0.446786) (xy 2.4003 -0.878586)
			)
			(stroke
				(width 0)
				(type default)
			)
			(fill yes)
			(layer "B.Fab")
		)
		(pad "1" smd rect
			(at 0.962406 -0.649986 270)
			(size 0.3302 1.1684)
			(layers "B.Cu" "B.Mask" "B.Paste")
			(net "FAN_7_PRESENT_R")
		)
		(pad "2" smd rect
			(at 0.962406 0 270)
			(size 0.3302 1.1684)
			(layers "B.Cu" "B.Mask" "B.Paste")
			(net "P52V_FAN_7_BUFF_EN_R")
		)
		(pad "3" smd rect
			(at 0.962406 0.649986 270)
			(size 0.3302 1.1684)
			(layers "B.Cu" "B.Mask" "B.Paste")
			(net "GND")
		)
		(pad "4" smd rect
			(at -0.962406 0.649986 270)
			(size 0.3302 1.1684)
			(layers "B.Cu" "B.Mask" "B.Paste")
			(net "P52V_FAN_7_EN")
		)
		(pad "5" smd rect
			(at -0.962406 -0.649986 270)
			(size 0.3302 1.1684)
			(layers "B.Cu" "B.Mask" "B.Paste")
			(net "P3V3_AUX")
		)
	)
	(footprint ""
		(layer "B.Cu")
		(at 44.069 -226.8728)
		(property "Reference" "PD8"
			(at -3.302 3.83667 0)
			(unlocked yes)
			(layer "B.SilkS")
			(effects
				(font
					(size 0.7874 0.5842)
					(thickness 0.1524)
				)
				(justify left mirror)
			)
		)
		(property "Value" ""
			(at 0 0 0)
			(layer "B.Fab")
			(effects
				(font
					(size 1.27 1.27)
				)
				(justify mirror)
			)
		)
		(duplicate_pad_numbers_are_jumpers no)
		(fp_line
			(start -5.334 0)
			(end -5.334 -3.109976)
			(stroke
				(width 0.1524)
				(type default)
			)
			(layer "B.SilkS")
		)
		(fp_line
			(start -5.334 3.109976)
			(end -5.334 0)
			(stroke
				(width 0.1524)
				(type default)
			)
			(layer "B.SilkS")
		)
		(fp_line
			(start -5.334 3.109976)
			(end -4.8133 3.109976)
			(stroke
				(width 0.1524)
				(type default)
			)
			(layer "B.SilkS")
		)
		(fp_line
			(start -5.207 3.109976)
			(end -5.207 -3.109976)
			(stroke
				(width 0.1524)
				(type default)
			)
			(layer "B.SilkS")
		)
		(fp_line
			(start -5.1308 3.109976)
			(end -5.1308 -3.109976)
			(stroke
				(width 0.1524)
				(type default)
			)
			(layer "B.SilkS")
		)
		(fp_line
			(start -5.0292 3.109976)
			(end -5.0292 -3.109976)
			(stroke
				(width 0.1524)
				(type default)
			)
			(layer "B.SilkS")
		)
		(fp_line
			(start -4.9276 3.109976)
			(end -4.9276 -3.109976)
			(stroke
				(width 0.1524)
				(type default)
			)
			(layer "B.SilkS")
		)
		(fp_line
			(start -4.826 -3.109976)
			(end -4.826 0)
			(stroke
				(width 0.1524)
				(type default)
			)
			(layer "B.SilkS")
		)
		(fp_line
			(start -4.826 0)
			(end -4.826 3.109976)
			(stroke
				(width 0.1524)
				(type default)
			)
			(layer "B.SilkS")
		)
		(fp_line
			(start -4.826 3.109976)
			(end 4.826 3.109976)
			(stroke
				(width 0.1524)
				(type default)
			)
			(layer "B.SilkS")
		)
		(fp_line
			(start -4.8133 -3.109976)
			(end -5.3467 -3.109976)
			(stroke
				(width 0.1524)
				(type default)
			)
			(layer "B.SilkS")
		)
		(fp_line
			(start -1.143 0)
			(end -1.8034 0)
			(stroke
				(width 0.1524)
				(type default)
			)
			(layer "B.SilkS")
		)
		(fp_line
			(start -1.143 0)
			(end 1.016 -1.016)
			(stroke
				(width 0.1524)
				(type default)
			)
			(layer "B.SilkS")
		)
		(fp_line
			(start -1.143 1.397)
			(end -1.143 -1.397)
			(stroke
				(width 0.1524)
				(type default)
			)
			(layer "B.SilkS")
		)
		(fp_line
			(start 1.016 -1.016)
			(end 1.016 1.016)
			(stroke
				(width 0.1524)
				(type default)
			)
			(layer "B.SilkS")
		)
		(fp_line
			(start 1.016 1.016)
			(end -1.016 0)
			(stroke
				(width 0.1524)
				(type default)
			)
			(layer "B.SilkS")
		)
		(fp_line
			(start 1.0922 0)
			(end 1.7018 0)
			(stroke
				(width 0.1524)
				(type default)
			)
			(layer "B.SilkS")
		)
		(fp_line
			(start 4.826 -3.109976)
			(end -4.826 -3.109976)
			(stroke
				(width 0.1524)
				(type default)
			)
			(layer "B.SilkS")
		)
		(fp_line
			(start 4.826 0)
			(end 4.826 -3.109976)
			(stroke
				(width 0.1524)
				(type default)
			)
			(layer "B.SilkS")
		)
		(fp_line
			(start 4.826 3.109976)
			(end 4.826 0)
			(stroke
				(width 0.1524)
				(type default)
			)
			(layer "B.SilkS")
		)
		(fp_line
			(start -3.554984 -3.109976)
			(end -3.554984 3.109976)
			(stroke
				(width 0.1)
				(type default)
			)
			(layer "B.Fab")
		)
		(fp_line
			(start -3.554984 3.109976)
			(end 3.554984 3.109976)
			(stroke
				(width 0.1)
				(type default)
			)
			(layer "B.Fab")
		)
		(fp_line
			(start -1.143 0)
			(end -1.8034 0)
			(stroke
				(width 0.1)
				(type default)
			)
			(layer "B.Fab")
		)
		(fp_line
			(start -1.143 0)
			(end 1.016 -1.016)
			(stroke
				(width 0.1)
				(type default)
			)
			(layer "B.Fab")
		)
		(fp_line
			(start -1.143 1.397)
			(end -1.143 -1.397)
			(stroke
				(width 0.1)
				(type default)
			)
			(layer "B.Fab")
		)
		(fp_line
			(start 1.016 -1.016)
			(end 1.016 1.016)
			(stroke
				(width 0.1)
				(type default)
			)
			(layer "B.Fab")
		)
		(fp_line
			(start 1.016 1.016)
			(end -1.016 0)
			(stroke
				(width 0.1)
				(type default)
			)
			(layer "B.Fab")
		)
		(fp_line
			(start 1.0922 0)
			(end 1.7018 0)
			(stroke
				(width 0.1)
				(type default)
			)
			(layer "B.Fab")
		)
		(fp_line
			(start 3.554984 -3.109976)
			(end -3.554984 -3.109976)
			(stroke
				(width 0.1)
				(type default)
			)
			(layer "B.Fab")
		)
		(fp_line
			(start 3.554984 3.109976)
			(end 3.554984 -3.109976)
			(stroke
				(width 0.1)
				(type default)
			)
			(layer "B.Fab")
		)
		(fp_text user "-"
			(at -6.731 1.79705 180)
			(unlocked yes)
			(layer "B.SilkS")
			(effects
				(font
					(size 1.905 1.4224)
					(thickness 0.1524)
				)
				(justify left mirror)
			)
		)
		(fp_text user "+"
			(at 5.207 0.65405 180)
			(unlocked yes)
			(layer "B.SilkS")
			(effects
				(font
					(size 1.905 1.4224)
					(thickness 0.1524)
				)
				(justify left mirror)
			)
		)
		(fp_text user "-"
			(at -6.6802 0.22225 180)
			(unlocked yes)
			(layer "B.Fab")
			(effects
				(font
					(size 1.905 1.4224)
					(thickness 0.1524)
				)
				(justify left mirror)
			)
		)
		(fp_text user "+"
			(at 4.5466 0.19685 180)
			(unlocked yes)
			(layer "B.Fab")
			(effects
				(font
					(size 1.905 1.4224)
					(thickness 0.1524)
				)
				(justify left mirror)
			)
		)
		(pad "A" smd rect
			(at 3.400044 0)
			(size 2.5146 3.302)
			(layers "B.Cu" "B.Mask" "B.Paste")
			(net "GND")
		)
		(pad "C" smd rect
			(at -3.400044 0)
			(size 2.5146 3.302)
			(layers "B.Cu" "B.Mask" "B.Paste")
			(net "P52V_FAN_1")
		)
	)
	(footprint ""
		(layer "B.Cu")
		(at 35.433 -64.837056 -90)
		(property "Reference" "PC21"
			(at 0 0 90)
			(layer "B.SilkS")
			(hide yes)
			(effects
				(font
					(size 1.27 1.27)
				)
				(justify mirror)
			)
		)
		(property "Value" ""
			(at 0 0 90)
			(layer "B.Fab")
			(effects
				(font
					(size 1.27 1.27)
				)
				(justify mirror)
			)
		)
		(duplicate_pad_numbers_are_jumpers no)
		(fp_line
			(start -0.7874 0.4064)
			(end 0.7874 0.4064)
			(stroke
				(width 0.1524)
				(type default)
			)
			(layer "B.SilkS")
		)
		(fp_line
			(start 0.7874 0.4064)
			(end 0.7874 -0.4064)
			(stroke
				(width 0.1524)
				(type default)
			)
			(layer "B.SilkS")
		)
		(fp_line
			(start -0.7874 -0.4064)
			(end -0.7874 0.4064)
			(stroke
				(width 0.1524)
				(type default)
			)
			(layer "B.SilkS")
		)
		(fp_line
			(start 0.7874 -0.4064)
			(end -0.7874 -0.4064)
			(stroke
				(width 0.1524)
				(type default)
			)
			(layer "B.SilkS")
		)
		(fp_line
			(start -0.67945 0.3048)
			(end -0.120396 0.3048)
			(stroke
				(width 0.1)
				(type default)
			)
			(layer "B.Fab")
		)
		(fp_line
			(start -0.120396 0.3048)
			(end -0.120396 0.2794)
			(stroke
				(width 0.1)
				(type default)
			)
			(layer "B.Fab")
		)
		(fp_line
			(start 0.12065 0.3048)
			(end 0.67945 0.3048)
			(stroke
				(width 0.1)
				(type default)
			)
			(layer "B.Fab")
		)
		(fp_line
			(start 0.67945 0.3048)
			(end 0.67945 -0.305054)
			(stroke
				(width 0.1)
				(type default)
			)
			(layer "B.Fab")
		)
		(fp_line
			(start -0.120396 0.2794)
			(end 0.12065 0.2794)
			(stroke
				(width 0.1)
				(type default)
			)
			(layer "B.Fab")
		)
		(fp_line
			(start 0.12065 0.2794)
			(end 0.12065 0.3048)
			(stroke
				(width 0.1)
				(type default)
			)
			(layer "B.Fab")
		)
		(fp_line
			(start -0.12065 -0.2794)
			(end -0.12065 -0.3048)
			(stroke
				(width 0.1)
				(type default)
			)
			(layer "B.Fab")
		)
		(fp_line
			(start 0.12065 -0.2794)
			(end -0.12065 -0.2794)
			(stroke
				(width 0.1)
				(type default)
			)
			(layer "B.Fab")
		)
		(fp_line
			(start -0.67945 -0.3048)
			(end -0.67945 0.3048)
			(stroke
				(width 0.1)
				(type default)
			)
			(layer "B.Fab")
		)
		(fp_line
			(start -0.12065 -0.3048)
			(end -0.67945 -0.3048)
			(stroke
				(width 0.1)
				(type default)
			)
			(layer "B.Fab")
		)
		(fp_line
			(start 0.12065 -0.305054)
			(end 0.12065 -0.2794)
			(stroke
				(width 0.1)
				(type default)
			)
			(layer "B.Fab")
		)
		(fp_line
			(start 0.67945 -0.305054)
			(end 0.12065 -0.305054)
			(stroke
				(width 0.1)
				(type default)
			)
			(layer "B.Fab")
		)
		(pad "1" smd circle
			(at 0.40005 0 90)
			(size 0 0)
			(layers "B.Cu" "B.Mask" "B.Paste")
			(net "FAN_3_TIMER")
		)
		(pad "2" smd circle
			(at -0.40005 0 90)
			(size 0 0)
			(layers "B.Cu" "B.Mask" "B.Paste")
			(net "GND")
		)
	)
)
